(kicad_pcb
	(version 20260206)
	(generator "pcbnew")
	(generator_version "10.0")
	(general
		(thickness 1.6)
		(legacy_teardrops no)
	)
	(paper "A4")
	(title_block
		(title "12092022_DA0F0TFB6D0_F0T_FAN_BOARD_MP5048_D_brd_v02_OCP.brd")
		(comment 1 "Grand Teton / footprints 441-446 of 924")
	)
	(layers
		(0 "F.Cu" signal "TOP")
		(4 "In1.Cu" signal "GND")
		(6 "In2.Cu" signal "IN1")
		(8 "In3.Cu" signal "IN2")
		(10 "In4.Cu" signal "GND1")
		(2 "B.Cu" signal "BOTTOM")
		(9 "F.Adhes" user "F.Adhesive")
		(11 "B.Adhes" user "B.Adhesive")
		(13 "F.Paste" user "Package Geometry/Pastemask Top")
		(15 "B.Paste" user "Package Geometry/Pastemask Bottom")
		(5 "F.SilkS" user "Ref Des/Silkscreen Top")
		(7 "B.SilkS" user "Ref Des/Silkscreen Bottom")
		(1 "F.Mask" user "Board Geometry/Soldermask Top")
		(3 "B.Mask" user "Board Geometry/Soldermask Bottom")
		(17 "Dwgs.User" user "User.Drawings")
		(19 "Cmts.User" user "User.Comments")
		(21 "Eco1.User" user "User.Eco1")
		(23 "Eco2.User" user "User.Eco2")
		(25 "Edge.Cuts" user "Board Geometry/Outline")
		(27 "Margin" user)
		(31 "F.CrtYd" user "Package Geometry/Place Bound Top")
		(29 "B.CrtYd" user "Package Geometry/Place Bound Bottom")
		(35 "F.Fab" user "Ref Des/Assembly Top")
		(33 "B.Fab" user "Ref Des/Assembly Bottom")
	)
	(footprint ""
		(layer "F.Cu")
		(at 17.907 -164.338 180)
		(property "Reference" "R5496"
			(at 0 0 180)
			(layer "F.SilkS")
			(hide yes)
			(effects
				(font
					(size 1.27 1.27)
				)
			)
		)
		(property "Value" ""
			(at 0 0 180)
			(layer "F.Fab")
			(effects
				(font
					(size 1.27 1.27)
				)
			)
		)
		(duplicate_pad_numbers_are_jumpers no)
		(fp_line
			(start 0.7874 0.4064)
			(end -0.7874 0.4064)
			(stroke
				(width 0.1524)
				(type default)
			)
			(layer "F.SilkS")
		)
		(fp_line
			(start 0.7874 -0.4064)
			(end 0.7874 0.4064)
			(stroke
				(width 0.1524)
				(type default)
			)
			(layer "F.SilkS")
		)
		(fp_line
			(start -0.7874 0.4064)
			(end -0.7874 -0.4064)
			(stroke
				(width 0.1524)
				(type default)
			)
			(layer "F.SilkS")
		)
		(fp_line
			(start -0.7874 -0.4064)
			(end 0.7874 -0.4064)
			(stroke
				(width 0.1524)
				(type default)
			)
			(layer "F.SilkS")
		)
		(fp_line
			(start 0.67945 0.3048)
			(end 0.120396 0.3048)
			(stroke
				(width 0.1)
				(type default)
			)
			(layer "F.Fab")
		)
		(fp_line
			(start 0.67945 -0.3048)
			(end 0.67945 0.3048)
			(stroke
				(width 0.1)
				(type default)
			)
			(layer "F.Fab")
		)
		(fp_line
			(start 0.12065 -0.2794)
			(end 0.12065 -0.3048)
			(stroke
				(width 0.1)
				(type default)
			)
			(layer "F.Fab")
		)
		(fp_line
			(start 0.12065 -0.3048)
			(end 0.67945 -0.3048)
			(stroke
				(width 0.1)
				(type default)
			)
			(layer "F.Fab")
		)
		(fp_line
			(start 0.120396 0.3048)
			(end 0.120396 0.2794)
			(stroke
				(width 0.1)
				(type default)
			)
			(layer "F.Fab")
		)
		(fp_line
			(start 0.120396 0.2794)
			(end -0.12065 0.2794)
			(stroke
				(width 0.1)
				(type default)
			)
			(layer "F.Fab")
		)
		(fp_line
			(start -0.12065 0.3048)
			(end -0.67945 0.3048)
			(stroke
				(width 0.1)
				(type default)
			)
			(layer "F.Fab")
		)
		(fp_line
			(start -0.12065 0.2794)
			(end -0.12065 0.3048)
			(stroke
				(width 0.1)
				(type default)
			)
			(layer "F.Fab")
		)
		(fp_line
			(start -0.12065 -0.2794)
			(end 0.12065 -0.2794)
			(stroke
				(width 0.1)
				(type default)
			)
			(layer "F.Fab")
		)
		(fp_line
			(start -0.12065 -0.305054)
			(end -0.12065 -0.2794)
			(stroke
				(width 0.1)
				(type default)
			)
			(layer "F.Fab")
		)
		(fp_line
			(start -0.67945 0.3048)
			(end -0.67945 -0.305054)
			(stroke
				(width 0.1)
				(type default)
			)
			(layer "F.Fab")
		)
		(fp_line
			(start -0.67945 -0.305054)
			(end -0.12065 -0.305054)
			(stroke
				(width 0.1)
				(type default)
			)
			(layer "F.Fab")
		)
		(pad "1" smd circle
			(at -0.40005 0 180)
			(size 0 0)
			(layers "F.Cu" "F.Mask" "F.Paste")
			(net "FAN_1_PRESENT_R_N")
		)
		(pad "2" smd circle
			(at 0.40005 0 180)
			(size 0 0)
			(layers "F.Cu" "F.Mask" "F.Paste")
			(net "FAN_1_PRESENT_N")
		)
	)
	(footprint ""
		(layer "F.Cu")
		(at 3.81 -184.658 180)
		(property "Reference" "R2355"
			(at 0 0 180)
			(layer "F.SilkS")
			(hide yes)
			(effects
				(font
					(size 1.27 1.27)
				)
			)
		)
		(property "Value" ""
			(at 0 0 180)
			(layer "F.Fab")
			(effects
				(font
					(size 1.27 1.27)
				)
			)
		)
		(duplicate_pad_numbers_are_jumpers no)
		(fp_line
			(start 0.7874 0.4064)
			(end -0.7874 0.4064)
			(stroke
				(width 0.1524)
				(type default)
			)
			(layer "F.SilkS")
		)
		(fp_line
			(start 0.7874 -0.4064)
			(end 0.7874 0.4064)
			(stroke
				(width 0.1524)
				(type default)
			)
			(layer "F.SilkS")
		)
		(fp_line
			(start -0.7874 0.4064)
			(end -0.7874 -0.4064)
			(stroke
				(width 0.1524)
				(type default)
			)
			(layer "F.SilkS")
		)
		(fp_line
			(start -0.7874 -0.4064)
			(end 0.7874 -0.4064)
			(stroke
				(width 0.1524)
				(type default)
			)
			(layer "F.SilkS")
		)
		(fp_line
			(start 0.67945 0.3048)
			(end 0.120396 0.3048)
			(stroke
				(width 0.1)
				(type default)
			)
			(layer "F.Fab")
		)
		(fp_line
			(start 0.67945 -0.3048)
			(end 0.67945 0.3048)
			(stroke
				(width 0.1)
				(type default)
			)
			(layer "F.Fab")
		)
		(fp_line
			(start 0.12065 -0.2794)
			(end 0.12065 -0.3048)
			(stroke
				(width 0.1)
				(type default)
			)
			(layer "F.Fab")
		)
		(fp_line
			(start 0.12065 -0.3048)
			(end 0.67945 -0.3048)
			(stroke
				(width 0.1)
				(type default)
			)
			(layer "F.Fab")
		)
		(fp_line
			(start 0.120396 0.3048)
			(end 0.120396 0.2794)
			(stroke
				(width 0.1)
				(type default)
			)
			(layer "F.Fab")
		)
		(fp_line
			(start 0.120396 0.2794)
			(end -0.12065 0.2794)
			(stroke
				(width 0.1)
				(type default)
			)
			(layer "F.Fab")
		)
		(fp_line
			(start -0.12065 0.3048)
			(end -0.67945 0.3048)
			(stroke
				(width 0.1)
				(type default)
			)
			(layer "F.Fab")
		)
		(fp_line
			(start -0.12065 0.2794)
			(end -0.12065 0.3048)
			(stroke
				(width 0.1)
				(type default)
			)
			(layer "F.Fab")
		)
		(fp_line
			(start -0.12065 -0.2794)
			(end 0.12065 -0.2794)
			(stroke
				(width 0.1)
				(type default)
			)
			(layer "F.Fab")
		)
		(fp_line
			(start -0.12065 -0.305054)
			(end -0.12065 -0.2794)
			(stroke
				(width 0.1)
				(type default)
			)
			(layer "F.Fab")
		)
		(fp_line
			(start -0.67945 0.3048)
			(end -0.67945 -0.305054)
			(stroke
				(width 0.1)
				(type default)
			)
			(layer "F.Fab")
		)
		(fp_line
			(start -0.67945 -0.305054)
			(end -0.12065 -0.305054)
			(stroke
				(width 0.1)
				(type default)
			)
			(layer "F.Fab")
		)
		(pad "1" smd circle
			(at -0.40005 0 180)
			(size 0 0)
			(layers "F.Cu" "F.Mask" "F.Paste")
			(net "PCA9555_MB0_A1")
		)
		(pad "2" smd circle
			(at 0.40005 0 180)
			(size 0 0)
			(layers "F.Cu" "F.Mask" "F.Paste")
			(net "GND")
		)
	)
	(footprint ""
		(layer "F.Cu")
		(at 43.18 -217.424)
		(property "Reference" "U406"
			(at -1.69926 2.03581 0)
			(unlocked yes)
			(layer "F.SilkS")
			(effects
				(font
					(size 0.7874 0.5842)
					(thickness 0.1524)
				)
				(justify left)
			)
		)
		(property "Value" ""
			(at 0 0 0)
			(layer "F.Fab")
			(effects
				(font
					(size 1.27 1.27)
				)
			)
		)
		(duplicate_pad_numbers_are_jumpers no)
		(fp_line
			(start -1.335278 -1.100074)
			(end -1.335278 1.100074)
			(stroke
				(width 0.1524)
				(type default)
			)
			(layer "F.SilkS")
		)
		(fp_line
			(start -1.335278 1.100074)
			(end 1.335278 1.100074)
			(stroke
				(width 0.1524)
				(type default)
			)
			(layer "F.SilkS")
		)
		(fp_line
			(start 1.335278 -1.100074)
			(end -1.335278 -1.100074)
			(stroke
				(width 0.1524)
				(type default)
			)
			(layer "F.SilkS")
		)
		(fp_line
			(start 1.335278 1.100074)
			(end 1.335278 -1.100074)
			(stroke
				(width 0.1524)
				(type default)
			)
			(layer "F.SilkS")
		)
		(fp_line
			(start -0.674878 -1.100074)
			(end -0.674878 1.100074)
			(stroke
				(width 0.1)
				(type default)
			)
			(layer "F.Fab")
		)
		(fp_line
			(start -0.674878 1.100074)
			(end 0.674878 1.100074)
			(stroke
				(width 0.1)
				(type default)
			)
			(layer "F.Fab")
		)
		(fp_line
			(start 0.674878 -1.100074)
			(end -0.674878 -1.100074)
			(stroke
				(width 0.1)
				(type default)
			)
			(layer "F.Fab")
		)
		(fp_line
			(start 0.674878 1.100074)
			(end 0.674878 -1.100074)
			(stroke
				(width 0.1)
				(type default)
			)
			(layer "F.Fab")
		)
		(pad "D" smd rect
			(at 0.8001 0 270)
			(size 0.6096 0.8128)
			(layers "F.Cu" "F.Mask" "F.Paste")
			(net "U406_D1")
		)
		(pad "G" smd rect
			(at -0.8001 -0.649986 270)
			(size 0.6096 0.8128)
			(layers "F.Cu" "F.Mask" "F.Paste")
			(net "FAN_1_PRESENT")
		)
		(pad "S" smd rect
			(at -0.8001 0.649986 270)
			(size 0.6096 0.8128)
			(layers "F.Cu" "F.Mask" "F.Paste")
			(net "GND")
		)
	)
	(footprint ""
		(layer "F.Cu")
		(at 8.382 -135.255 -90)
		(property "Reference" "R5570"
			(at 0 0 270)
			(layer "F.SilkS")
			(hide yes)
			(effects
				(font
					(size 1.27 1.27)
				)
			)
		)
		(property "Value" ""
			(at 0 0 270)
			(layer "F.Fab")
			(effects
				(font
					(size 1.27 1.27)
				)
			)
		)
		(duplicate_pad_numbers_are_jumpers no)
		(fp_line
			(start -0.7874 0.4064)
			(end -0.7874 -0.4064)
			(stroke
				(width 0.1524)
				(type default)
			)
			(layer "F.SilkS")
		)
		(fp_line
			(start 0.7874 0.4064)
			(end -0.7874 0.4064)
			(stroke
				(width 0.1524)
				(type default)
			)
			(layer "F.SilkS")
		)
		(fp_line
			(start -0.7874 -0.4064)
			(end 0.7874 -0.4064)
			(stroke
				(width 0.1524)
				(type default)
			)
			(layer "F.SilkS")
		)
		(fp_line
			(start 0.7874 -0.4064)
			(end 0.7874 0.4064)
			(stroke
				(width 0.1524)
				(type default)
			)
			(layer "F.SilkS")
		)
		(fp_line
			(start -0.67945 0.3048)
			(end -0.67945 -0.305054)
			(stroke
				(width 0.1)
				(type default)
			)
			(layer "F.Fab")
		)
		(fp_line
			(start -0.12065 0.3048)
			(end -0.67945 0.3048)
			(stroke
				(width 0.1)
				(type default)
			)
			(layer "F.Fab")
		)
		(fp_line
			(start 0.120396 0.3048)
			(end 0.120396 0.2794)
			(stroke
				(width 0.1)
				(type default)
			)
			(layer "F.Fab")
		)
		(fp_line
			(start 0.67945 0.3048)
			(end 0.120396 0.3048)
			(stroke
				(width 0.1)
				(type default)
			)
			(layer "F.Fab")
		)
		(fp_line
			(start -0.12065 0.2794)
			(end -0.12065 0.3048)
			(stroke
				(width 0.1)
				(type default)
			)
			(layer "F.Fab")
		)
		(fp_line
			(start 0.120396 0.2794)
			(end -0.12065 0.2794)
			(stroke
				(width 0.1)
				(type default)
			)
			(layer "F.Fab")
		)
		(fp_line
			(start -0.12065 -0.2794)
			(end 0.12065 -0.2794)
			(stroke
				(width 0.1)
				(type default)
			)
			(layer "F.Fab")
		)
		(fp_line
			(start 0.12065 -0.2794)
			(end 0.12065 -0.3048)
			(stroke
				(width 0.1)
				(type default)
			)
			(layer "F.Fab")
		)
		(fp_line
			(start 0.12065 -0.3048)
			(end 0.67945 -0.3048)
			(stroke
				(width 0.1)
				(type default)
			)
			(layer "F.Fab")
		)
		(fp_line
			(start 0.67945 -0.3048)
			(end 0.67945 0.3048)
			(stroke
				(width 0.1)
				(type default)
			)
			(layer "F.Fab")
		)
		(fp_line
			(start -0.67945 -0.305054)
			(end -0.12065 -0.305054)
			(stroke
				(width 0.1)
				(type default)
			)
			(layer "F.Fab")
		)
		(fp_line
			(start -0.12065 -0.305054)
			(end -0.12065 -0.2794)
			(stroke
				(width 0.1)
				(type default)
			)
			(layer "F.Fab")
		)
		(pad "1" smd circle
			(at -0.40005 0 270)
			(size 0 0)
			(layers "F.Cu" "F.Mask" "F.Paste")
			(net "GND")
		)
		(pad "2" smd circle
			(at 0.40005 0 270)
			(size 0 0)
			(layers "F.Cu" "F.Mask" "F.Paste")
			(net "U404_ADD0")
		)
	)
	(footprint ""
		(layer "F.Cu")
		(at 47.244 -186.182)
		(property "Reference" "C2086"
			(at 0 0 0)
			(layer "F.SilkS")
			(hide yes)
			(effects
				(font
					(size 1.27 1.27)
				)
			)
		)
		(property "Value" ""
			(at 0 0 0)
			(layer "F.Fab")
			(effects
				(font
					(size 1.27 1.27)
				)
			)
		)
		(duplicate_pad_numbers_are_jumpers no)
		(fp_line
			(start -0.7874 -0.4064)
			(end 0.7874 -0.4064)
			(stroke
				(width 0.1524)
				(type default)
			)
			(layer "F.SilkS")
		)
		(fp_line
			(start -0.7874 0.4064)
			(end -0.7874 -0.4064)
			(stroke
				(width 0.1524)
				(type default)
			)
			(layer "F.SilkS")
		)
		(fp_line
			(start 0.7874 -0.4064)
			(end 0.7874 0.4064)
			(stroke
				(width 0.1524)
				(type default)
			)
			(layer "F.SilkS")
		)
		(fp_line
			(start 0.7874 0.4064)
			(end -0.7874 0.4064)
			(stroke
				(width 0.1524)
				(type default)
			)
			(layer "F.SilkS")
		)
		(fp_line
			(start -0.67945 -0.305054)
			(end -0.12065 -0.305054)
			(stroke
				(width 0.1)
				(type default)
			)
			(layer "F.Fab")
		)
		(fp_line
			(start -0.67945 0.3048)
			(end -0.67945 -0.305054)
			(stroke
				(width 0.1)
				(type default)
			)
			(layer "F.Fab")
		)
		(fp_line
			(start -0.12065 -0.305054)
			(end -0.12065 -0.2794)
			(stroke
				(width 0.1)
				(type default)
			)
			(layer "F.Fab")
		)
		(fp_line
			(start -0.12065 -0.2794)
			(end 0.12065 -0.2794)
			(stroke
				(width 0.1)
				(type default)
			)
			(layer "F.Fab")
		)
		(fp_line
			(start -0.12065 0.2794)
			(end -0.12065 0.3048)
			(stroke
				(width 0.1)
				(type default)
			)
			(layer "F.Fab")
		)
		(fp_line
			(start -0.12065 0.3048)
			(end -0.67945 0.3048)
			(stroke
				(width 0.1)
				(type default)
			)
			(layer "F.Fab")
		)
		(fp_line
			(start 0.120396 0.2794)
			(end -0.12065 0.2794)
			(stroke
				(width 0.1)
				(type default)
			)
			(layer "F.Fab")
		)
		(fp_line
			(start 0.120396 0.3048)
			(end 0.120396 0.2794)
			(stroke
				(width 0.1)
				(type default)
			)
			(layer "F.Fab")
		)
		(fp_line
			(start 0.12065 -0.3048)
			(end 0.67945 -0.3048)
			(stroke
				(width 0.1)
				(type default)
			)
			(layer "F.Fab")
		)
		(fp_line
			(start 0.12065 -0.2794)
			(end 0.12065 -0.3048)
			(stroke
				(width 0.1)
				(type default)
			)
			(layer "F.Fab")
		)
		(fp_line
			(start 0.67945 -0.3048)
			(end 0.67945 0.3048)
			(stroke
				(width 0.1)
				(type default)
			)
			(layer "F.Fab")
		)
		(fp_line
			(start 0.67945 0.3048)
			(end 0.120396 0.3048)
			(stroke
				(width 0.1)
				(type default)
			)
			(layer "F.Fab")
		)
		(pad "1" smd circle
			(at -0.40005 0)
			(size 0 0)
			(layers "F.Cu" "F.Mask" "F.Paste")
			(net "P52V_FAN_7_BUFF_EN_R")
		)
		(pad "2" smd circle
			(at 0.40005 0)
			(size 0 0)
			(layers "F.Cu" "F.Mask" "F.Paste")
			(net "GND")
		)
	)
	(footprint ""
		(layer "F.Cu")
		(at 38.6461 -124.968)
		(property "Reference" "R5583"
			(at 0 0 0)
			(layer "F.SilkS")
			(hide yes)
			(effects
				(font
					(size 1.27 1.27)
				)
			)
		)
		(property "Value" ""
			(at 0 0 0)
			(layer "F.Fab")
			(effects
				(font
					(size 1.27 1.27)
				)
			)
		)
		(duplicate_pad_numbers_are_jumpers no)
		(fp_line
			(start -0.7874 -0.4064)
			(end 0.7874 -0.4064)
			(stroke
				(width 0.1524)
				(type default)
			)
			(layer "F.SilkS")
		)
		(fp_line
			(start -0.7874 0.4064)
			(end -0.7874 -0.4064)
			(stroke
				(width 0.1524)
				(type default)
			)
			(layer "F.SilkS")
		)
		(fp_line
			(start 0.7874 -0.4064)
			(end 0.7874 0.4064)
			(stroke
				(width 0.1524)
				(type default)
			)
			(layer "F.SilkS")
		)
		(fp_line
			(start 0.7874 0.4064)
			(end -0.7874 0.4064)
			(stroke
				(width 0.1524)
				(type default)
			)
			(layer "F.SilkS")
		)
		(fp_line
			(start -0.67945 -0.305054)
			(end -0.12065 -0.305054)
			(stroke
				(width 0.1)
				(type default)
			)
			(layer "F.Fab")
		)
		(fp_line
			(start -0.67945 0.3048)
			(end -0.67945 -0.305054)
			(stroke
				(width 0.1)
				(type default)
			)
			(layer "F.Fab")
		)
		(fp_line
			(start -0.12065 -0.305054)
			(end -0.12065 -0.2794)
			(stroke
				(width 0.1)
				(type default)
			)
			(layer "F.Fab")
		)
		(fp_line
			(start -0.12065 -0.2794)
			(end 0.12065 -0.2794)
			(stroke
				(width 0.1)
				(type default)
			)
			(layer "F.Fab")
		)
		(fp_line
			(start -0.12065 0.2794)
			(end -0.12065 0.3048)
			(stroke
				(width 0.1)
				(type default)
			)
			(layer "F.Fab")
		)
		(fp_line
			(start -0.12065 0.3048)
			(end -0.67945 0.3048)
			(stroke
				(width 0.1)
				(type default)
			)
			(layer "F.Fab")
		)
		(fp_line
			(start 0.120396 0.2794)
			(end -0.12065 0.2794)
			(stroke
				(width 0.1)
				(type default)
			)
			(layer "F.Fab")
		)
		(fp_line
			(start 0.120396 0.3048)
			(end 0.120396 0.2794)
			(stroke
				(width 0.1)
				(type default)
			)
			(layer "F.Fab")
		)
		(fp_line
			(start 0.12065 -0.3048)
			(end 0.67945 -0.3048)
			(stroke
				(width 0.1)
				(type default)
			)
			(layer "F.Fab")
		)
		(fp_line
			(start 0.12065 -0.2794)
			(end 0.12065 -0.3048)
			(stroke
				(width 0.1)
				(type default)
			)
			(layer "F.Fab")
		)
		(fp_line
			(start 0.67945 -0.3048)
			(end 0.67945 0.3048)
			(stroke
				(width 0.1)
				(type default)
			)
			(layer "F.Fab")
		)
		(fp_line
			(start 0.67945 0.3048)
			(end 0.120396 0.3048)
			(stroke
				(width 0.1)
				(type default)
			)
			(layer "F.Fab")
		)
		(pad "1" smd rect
			(at -0.40005 0 180)
			(size 0.4572 0.508)
			(layers "F.Cu" "F.Mask" "F.Paste")
			(net "FAN_3_PWM")
		)
		(pad "2" smd rect
			(at 0.40005 0 180)
			(size 0.4572 0.508)
			(layers "F.Cu" "F.Mask" "F.Paste")
			(net "FAN_3_PWM_R2")
		)
	)
)
